FILE_TYPE = CONNECTIVITY;
{Allegro Design Entry HDL 16.6-p007 (v16-6-112F) 10/10/2012}
"PAGE_NUMBER" = 106;
0"NC";
1"P3E_CPU0_PE3_OCP_TXN<15:0>";
2"P3E_CPU0_PE3_OCP_TXP<15:0>";
3"P3E_OCP_CPU0_PE3_C_TXP<15:0>";
4"P3E_OCP_CPU0_PE3_C_TXN<15:0>";
5"P3E_OCP_CPU0_PE3_C_TXN<15>";
6"P3E_CPU0_PE3_OCP_TXN<15>";
7"P3E_OCP_CPU0_PE3_C_TXN<14>";
8"P3E_CPU0_PE3_OCP_TXN<14>";
9"P3E_OCP_CPU0_PE3_C_TXN<13>";
10"P3E_OCP_CPU0_PE3_C_TXN<11>";
11"P3E_CPU0_PE3_OCP_TXN<13>";
12"P3E_CPU0_PE3_OCP_TXN<11>";
13"P3E_OCP_CPU0_PE3_C_TXN<12>";
14"P3E_CPU0_PE3_OCP_TXN<12>";
15"P3E_OCP_CPU0_PE3_C_TXP<15>";
16"P3E_OCP_CPU0_PE3_C_TXP<13>";
17"P3E_OCP_CPU0_PE3_C_TXP<14>";
18"P3E_CPU0_PE3_OCP_TXP<13>";
19"P3E_CPU0_PE3_OCP_TXP<15>";
20"P3E_CPU0_PE3_OCP_TXP<14>";
21"P3E_OCP_CPU0_PE3_C_TXP<12>";
22"P3E_OCP_CPU0_PE3_C_TXP<11>";
23"P3E_CPU0_PE3_OCP_TXP<11>";
24"P3E_CPU0_PE3_OCP_TXP<12>";
25"P3E_OCP_CPU0_PE3_C_TXN<9>";
26"P3E_OCP_CPU0_PE3_C_TXN<8>";
27"P3E_OCP_CPU0_PE3_C_TXN<10>";
28"P3E_CPU0_PE3_OCP_TXN<9>";
29"P3E_CPU0_PE3_OCP_TXN<10>";
30"P3E_CPU0_PE3_OCP_TXN<8>";
31"P3E_OCP_CPU0_PE3_C_TXN<7>";
32"P3E_CPU0_PE3_OCP_TXN<7>";
33"P3E_OCP_CPU0_PE3_C_TXN<6>";
34"P3E_CPU0_PE3_OCP_TXN<6>";
35"P3E_OCP_CPU0_PE3_C_TXN<5>";
36"P3E_OCP_CPU0_PE3_C_TXN<3>";
37"P3E_OCP_CPU0_PE3_C_TXN<4>";
38"P3E_CPU0_PE3_OCP_TXN<5>";
39"P3E_CPU0_PE3_OCP_TXN<3>";
40"P3E_CPU0_PE3_OCP_TXN<4>";
41"P3E_OCP_CPU0_PE3_C_TXN<1>";
42"P3E_CPU0_PE3_OCP_TXN<1>";
43"P3E_OCP_CPU0_PE3_C_TXN<2>";
44"P3E_CPU0_PE3_OCP_TXN<2>";
45"P3E_OCP_CPU0_PE3_C_TXP<9>";
46"P3E_OCP_CPU0_PE3_C_TXP<10>";
47"P3E_OCP_CPU0_PE3_C_TXP<8>";
48"P3E_CPU0_PE3_OCP_TXP<9>";
49"P3E_CPU0_PE3_OCP_TXP<10>";
50"P3E_CPU0_PE3_OCP_TXP<8>";
51"P3E_OCP_CPU0_PE3_C_TXP<7>";
52"P3E_OCP_CPU0_PE3_C_TXP<6>";
53"P3E_CPU0_PE3_OCP_TXP<7>";
54"P3E_CPU0_PE3_OCP_TXP<6>";
55"P3E_OCP_CPU0_PE3_C_TXP<5>";
56"P3E_OCP_CPU0_PE3_C_TXP<4>";
57"P3E_OCP_CPU0_PE3_C_TXP<3>";
58"P3E_CPU0_PE3_OCP_TXP<5>";
59"P3E_CPU0_PE3_OCP_TXP<3>";
60"P3E_CPU0_PE3_OCP_TXP<4>";
61"P3E_OCP_CPU0_PE3_C_TXP<2>";
62"P3E_OCP_CPU0_PE3_C_TXP<1>";
63"P3E_OCP_CPU0_PE3_C_TXP<0>";
64"P3E_CPU0_PE3_OCP_TXP<1>";
65"P3E_CPU0_PE3_OCP_TXP<2>";
66"P3E_CPU0_PE3_OCP_TXP<0>";
67"P3E_OCP_CPU0_PE3_C_TXN<0>";
68"P3E_CPU0_PE3_OCP_TXN<0>";
%"CAP"
"1","(-4100,2650)","2","mstr_discrete","I10";
;
ROOM"PCIE_STEERING"
CDS_LOCATION"C1R2"
$SEC"1"
CDS_SEC"1"
CDS_LIB"mstr_discrete"
BOM_COST"IO_SLOT"
MATERIAL"X7R"
VOLTAGE"16V"
PACK_TYPE"0402"
TOLERANCE"10%"
VALUE"0.22UF"
PART_NUMBER"A36096-155"
LOCATION"C1R2";
"A"
$PN"1"66;
"B"
$PN"2"63;
%"CAP"
"1","(-6500,2650)","2","mstr_discrete","I100";
;
ROOM"PCIE_STEERING"
CDS_LOCATION"C1M12"
$SEC"1"
CDS_SEC"1"
BOM_COST"IO_SLOT"
CDS_LIB"mstr_discrete"
MATERIAL"X7R"
VOLTAGE"16V"
PACK_TYPE"0402"
TOLERANCE"10%"
VALUE"0.22UF"
PART_NUMBER"A36096-155"
LOCATION"C1M12";
"A"
$PN"1"24;
"B"
$PN"2"21;
%"TAP"
"7","(-6500,2100)","0","mstr_standard","I101";
;
HDL_TAP"TRUE"
BODY_TYPE"PLUMBING"
CDS_LIB"mstr_standard";
"B \NAC \NWC"3;
"S \NAC"
BN"12"21;
%"CAP"
"1","(-6700,2350)","2","mstr_discrete","I102";
;
ROOM"PCIE_STEERING"
CDS_LOCATION"C1M10"
$SEC"1"
CDS_SEC"1"
BOM_COST"IO_SLOT"
CDS_LIB"mstr_discrete"
MATERIAL"X7R"
VOLTAGE"16V"
PACK_TYPE"0402"
TOLERANCE"10%"
VALUE"0.22UF"
PART_NUMBER"A36096-155"
LOCATION"C1M10";
"A"
$PN"1"18;
"B"
$PN"2"16;
%"TAP"
"7","(-6700,2100)","0","mstr_standard","I103";
;
HDL_TAP"TRUE"
BODY_TYPE"PLUMBING"
CDS_LIB"mstr_standard";
"B \NAC \NWC"3;
"S \NAC"
BN"13"16;
%"TAP"
"7","(-6900,2100)","0","mstr_standard","I104";
;
HDL_TAP"TRUE"
BODY_TYPE"PLUMBING"
CDS_LIB"mstr_standard";
"B \NAC \NWC"3;
"S \NAC"
BN"14"17;
%"CAP"
"1","(-6900,2650)","2","mstr_discrete","I105";
;
ROOM"PCIE_STEERING"
CDS_LOCATION"C1M8"
$SEC"1"
CDS_SEC"1"
CDS_LIB"mstr_discrete"
MATERIAL"X7R"
VOLTAGE"16V"
PACK_TYPE"0402"
TOLERANCE"10%"
VALUE"0.22UF"
PART_NUMBER"A36096-155"
LOCATION"C1M8";
"A"
$PN"1"20;
"B"
$PN"2"17;
%"TAP"
"3","(-7100,2900)","0","mstr_standard","I106";
;
HDL_TAP"TRUE"
BODY_TYPE"PLUMBING"
CDS_LIB"mstr_standard";
"B \NAC \NWC"2;
"S \NAC"
BN"15"19;
%"TAP"
"7","(-7100,2100)","0","mstr_standard","I108";
;
HDL_TAP"TRUE"
BODY_TYPE"PLUMBING"
CDS_LIB"mstr_standard";
"B \NAC \NWC"3;
"S \NAC"
BN"15"15;
%"CAP"
"1","(-7100,2350)","2","mstr_discrete","I109";
;
ROOM"PCIE_STEERING"
CDS_LOCATION"C1M6"
$SEC"1"
CDS_SEC"1"
CDS_LIB"mstr_discrete"
MATERIAL"X7R"
VOLTAGE"16V"
PACK_TYPE"0402"
TOLERANCE"10%"
VALUE"0.22UF"
PART_NUMBER"A36096-155"
LOCATION"C1M6";
"A"
$PN"1"19;
"B"
$PN"2"15;
%"TAP"
"3","(-4300,2900)","0","mstr_standard","I11";
;
HDL_TAP"TRUE"
BODY_TYPE"PLUMBING"
CDS_LIB"mstr_standard";
"B \NAC \NWC"2;
"S \NAC"
BN"1"64;
%"TAP"
"3","(-6450,1900)","0","mstr_standard","I110";
;
HDL_TAP"TRUE"
BODY_TYPE"PLUMBING"
CDS_LIB"mstr_standard";
"B \NAC \NWC"1;
"S \NAC"
BN"12"14;
%"CAP"
"1","(-6450,1650)","2","mstr_discrete","I111";
;
ROOM"PCIE_STEERING"
CDS_LOCATION"C1M13"
$SEC"1"
CDS_SEC"1"
BOM_COST"IO_SLOT"
CDS_LIB"mstr_discrete"
MATERIAL"X7R"
VOLTAGE"16V"
PACK_TYPE"0402"
TOLERANCE"10%"
VALUE"0.22UF"
PART_NUMBER"A36096-155"
LOCATION"C1M13";
"A"
$PN"1"14;
"B"
$PN"2"13;
%"TAP"
"3","(-6650,1900)","0","mstr_standard","I112";
;
HDL_TAP"TRUE"
BODY_TYPE"PLUMBING"
CDS_LIB"mstr_standard";
"B \NAC \NWC"1;
"S \NAC"
BN"13"11;
%"TAP"
"3","(-6850,1900)","0","mstr_standard","I113";
;
HDL_TAP"TRUE"
BODY_TYPE"PLUMBING"
CDS_LIB"mstr_standard";
"B \NAC \NWC"1;
"S \NAC"
BN"14"8;
%"CAP"
"1","(-6850,1650)","2","mstr_discrete","I114";
;
ROOM"PCIE_STEERING"
CDS_LOCATION"C1M9"
$SEC"1"
CDS_SEC"1"
CDS_LIB"mstr_discrete"
MATERIAL"X7R"
VOLTAGE"16V"
PACK_TYPE"0402"
TOLERANCE"10%"
VALUE"0.22UF"
PART_NUMBER"A36096-155"
LOCATION"C1M9";
"A"
$PN"1"8;
"B"
$PN"2"7;
%"TAP"
"7","(-6450,1100)","0","mstr_standard","I115";
;
HDL_TAP"TRUE"
BODY_TYPE"PLUMBING"
CDS_LIB"mstr_standard";
"B \NAC \NWC"4;
"S \NAC"
BN"12"13;
%"TAP"
"7","(-6650,1100)","0","mstr_standard","I116";
;
HDL_TAP"TRUE"
BODY_TYPE"PLUMBING"
CDS_LIB"mstr_standard";
"B \NAC \NWC"4;
"S \NAC"
BN"13"9;
%"CAP"
"1","(-6650,1350)","2","mstr_discrete","I117";
;
ROOM"PCIE_STEERING"
CDS_LOCATION"C1M11"
$SEC"1"
CDS_SEC"1"
BOM_COST"IO_SLOT"
CDS_LIB"mstr_discrete"
MATERIAL"X7R"
VOLTAGE"16V"
PACK_TYPE"0402"
TOLERANCE"10%"
VALUE"0.22UF"
PART_NUMBER"A36096-155"
LOCATION"C1M11";
"A"
$PN"1"11;
"B"
$PN"2"9;
%"TAP"
"7","(-6850,1100)","0","mstr_standard","I118";
;
HDL_TAP"TRUE"
BODY_TYPE"PLUMBING"
CDS_LIB"mstr_standard";
"B \NAC \NWC"4;
"S \NAC"
BN"14"7;
%"TAP"
"3","(-7050,1900)","0","mstr_standard","I119";
;
HDL_TAP"TRUE"
BODY_TYPE"PLUMBING"
CDS_LIB"mstr_standard";
"B \NAC \NWC"1;
"S \NAC"
BN"15"6;
%"TAP"
"7","(-7050,1100)","0","mstr_standard","I121";
;
HDL_TAP"TRUE"
BODY_TYPE"PLUMBING"
CDS_LIB"mstr_standard";
"B \NAC \NWC"4;
"S \NAC"
BN"15"5;
%"CAP"
"1","(-7050,1350)","2","mstr_discrete","I122";
;
ROOM"PCIE_STEERING"
CDS_LOCATION"C1M7"
$SEC"1"
CDS_SEC"1"
CDS_LIB"mstr_discrete"
MATERIAL"X7R"
VOLTAGE"16V"
PACK_TYPE"0402"
TOLERANCE"10%"
VALUE"0.22UF"
PART_NUMBER"A36096-155"
LOCATION"C1M7";
"A"
$PN"1"6;
"B"
$PN"2"5;
%"CAP"
"1","(-5275,1650)","2","mstr_discrete","I123";
;
ROOM"PCIE_STEERING"
CDS_LOCATION"C2R7"
$SEC"1"
CDS_SEC"1"
BOM_COST"IO_SLOT"
CDS_LIB"mstr_discrete"
MATERIAL"X7R"
VOLTAGE"16V"
PACK_TYPE"0402"
TOLERANCE"10%"
VALUE"0.22UF"
PART_NUMBER"A36096-155"
LOCATION"C2R7";
"A"
$PN"1"34;
"B"
$PN"2"33;
%"TAP"
"7","(-5300,2100)","0","mstr_standard","I124";
;
HDL_TAP"TRUE"
BODY_TYPE"PLUMBING"
CDS_LIB"mstr_standard";
"B \NAC \NWC"3;
"S \NAC"
BN"6"52;
%"TAP"
"3","(-5500,2900)","0","mstr_standard","I125";
;
HDL_TAP"TRUE"
BODY_TYPE"PLUMBING"
CDS_LIB"mstr_standard";
"B \NAC \NWC"2;
"S \NAC"
BN"7"53;
%"TAP"
"3","(-4900,2900)","0","mstr_standard","I126";
;
HDL_TAP"TRUE"
BODY_TYPE"PLUMBING"
CDS_LIB"mstr_standard";
"B \NAC \NWC"2;
"S \NAC"
BN"4"60;
%"TAP"
"3","(-5100,2900)","0","mstr_standard","I127";
;
HDL_TAP"TRUE"
BODY_TYPE"PLUMBING"
CDS_LIB"mstr_standard";
"B \NAC \NWC"2;
"S \NAC"
BN"5"58;
%"CAP"
"1","(-4900,2650)","2","mstr_discrete","I128";
;
ROOM"PCIE_STEERING"
CDS_LOCATION"C1R10"
$SEC"1"
CDS_SEC"1"
BOM_COST"IO_SLOT"
CDS_LIB"mstr_discrete"
MATERIAL"X7R"
VOLTAGE"16V"
PACK_TYPE"0402"
TOLERANCE"10%"
VALUE"0.22UF"
PART_NUMBER"A36096-155"
LOCATION"C1R10";
"A"
$PN"1"60;
"B"
$PN"2"56;
%"TAP"
"7","(-4900,2100)","0","mstr_standard","I129";
;
HDL_TAP"TRUE"
BODY_TYPE"PLUMBING"
CDS_LIB"mstr_standard";
"B \NAC \NWC"3;
"S \NAC"
BN"4"56;
%"CAP"
"1","(-5100,2350)","2","mstr_discrete","I130";
;
CDS_LOCATION"C2R14"
ROOM"PCIE_STEERING"
$SEC"1"
CDS_SEC"1"
BOM_COST"IO_SLOT"
CDS_LIB"mstr_discrete"
MATERIAL"X7R"
VOLTAGE"16V"
PACK_TYPE"0402"
TOLERANCE"10%"
VALUE"0.22UF"
PART_NUMBER"A36096-155"
LOCATION"C2R14";
"A"
$PN"1"58;
"B"
$PN"2"55;
%"TAP"
"7","(-5100,2100)","0","mstr_standard","I131";
;
HDL_TAP"TRUE"
BODY_TYPE"PLUMBING"
CDS_LIB"mstr_standard";
"B \NAC \NWC"3;
"S \NAC"
BN"5"55;
%"TAP"
"3","(-4875,1900)","0","mstr_standard","I133";
;
HDL_TAP"TRUE"
BODY_TYPE"PLUMBING"
CDS_LIB"mstr_standard";
"B \NAC \NWC"1;
"S \NAC"
BN"4"40;
%"CAP"
"1","(-4875,1650)","2","mstr_discrete","I134";
;
ROOM"PCIE_STEERING"
CDS_LOCATION"C1R9"
$SEC"1"
CDS_SEC"1"
BOM_COST"IO_SLOT"
CDS_LIB"mstr_discrete"
MATERIAL"X7R"
VOLTAGE"16V"
PACK_TYPE"0402"
TOLERANCE"10%"
VALUE"0.22UF"
PART_NUMBER"A36096-155"
LOCATION"C1R9";
"A"
$PN"1"40;
"B"
$PN"2"37;
%"TAP"
"3","(-5075,1900)","0","mstr_standard","I135";
;
HDL_TAP"TRUE"
BODY_TYPE"PLUMBING"
CDS_LIB"mstr_standard";
"B \NAC \NWC"1;
"S \NAC"
BN"5"38;
%"TAP"
"7","(-4875,1100)","0","mstr_standard","I136";
;
HDL_TAP"TRUE"
BODY_TYPE"PLUMBING"
CDS_LIB"mstr_standard";
"B \NAC \NWC"4;
"S \NAC"
BN"4"37;
%"CAP"
"1","(-5075,1350)","2","mstr_discrete","I137";
;
CDS_LOCATION"C2R13"
ROOM"PCIE_STEERING"
$SEC"1"
CDS_SEC"1"
BOM_COST"IO_SLOT"
CDS_LIB"mstr_discrete"
MATERIAL"X7R"
VOLTAGE"16V"
PACK_TYPE"0402"
TOLERANCE"10%"
VALUE"0.22UF"
PART_NUMBER"A36096-155"
LOCATION"C2R13";
"A"
$PN"1"38;
"B"
$PN"2"35;
%"TAP"
"7","(-5075,1100)","0","mstr_standard","I138";
;
HDL_TAP"TRUE"
BODY_TYPE"PLUMBING"
CDS_LIB"mstr_standard";
"B \NAC \NWC"4;
"S \NAC"
BN"5"35;
%"TAP"
"3","(-5300,2900)","0","mstr_standard","I140";
;
HDL_TAP"TRUE"
BODY_TYPE"PLUMBING"
CDS_LIB"mstr_standard";
"B \NAC \NWC"2;
"S \NAC"
BN"6"54;
%"CAP"
"1","(-5300,2650)","2","mstr_discrete","I141";
;
ROOM"PCIE_STEERING"
CDS_LOCATION"C2R8"
$SEC"1"
CDS_SEC"1"
BOM_COST"IO_SLOT"
CDS_LIB"mstr_discrete"
MATERIAL"X7R"
VOLTAGE"16V"
PACK_TYPE"0402"
TOLERANCE"10%"
VALUE"0.22UF"
PART_NUMBER"A36096-155"
LOCATION"C2R8";
"A"
$PN"1"54;
"B"
$PN"2"52;
%"CAP"
"1","(-5500,2350)","2","mstr_discrete","I142";
;
ROOM"PCIE_STEERING"
CDS_LOCATION"C2R10"
$SEC"1"
CDS_SEC"1"
BOM_COST"IO_SLOT"
CDS_LIB"mstr_discrete"
MATERIAL"X7R"
VOLTAGE"16V"
PACK_TYPE"0402"
TOLERANCE"10%"
VALUE"0.22UF"
PART_NUMBER"A36096-155"
LOCATION"C2R10";
"A"
$PN"1"53;
"B"
$PN"2"51;
%"TAP"
"7","(-5500,2100)","0","mstr_standard","I143";
;
HDL_TAP"TRUE"
BODY_TYPE"PLUMBING"
CDS_LIB"mstr_standard";
"B \NAC \NWC"3;
"S \NAC"
BN"7"51;
%"TAP"
"3","(-5275,1900)","0","mstr_standard","I144";
;
HDL_TAP"TRUE"
BODY_TYPE"PLUMBING"
CDS_LIB"mstr_standard";
"B \NAC \NWC"1;
"S \NAC"
BN"6"34;
%"TAP"
"3","(-5475,1900)","0","mstr_standard","I145";
;
HDL_TAP"TRUE"
BODY_TYPE"PLUMBING"
CDS_LIB"mstr_standard";
"B \NAC \NWC"1;
"S \NAC"
BN"7"32;
%"TAP"
"7","(-5275,1100)","0","mstr_standard","I146";
;
HDL_TAP"TRUE"
BODY_TYPE"PLUMBING"
CDS_LIB"mstr_standard";
"B \NAC \NWC"4;
"S \NAC"
BN"6"33;
%"CAP"
"1","(-5475,1350)","2","mstr_discrete","I147";
;
ROOM"PCIE_STEERING"
CDS_LOCATION"C2R9"
$SEC"1"
CDS_SEC"1"
BOM_COST"IO_SLOT"
CDS_LIB"mstr_discrete"
MATERIAL"X7R"
VOLTAGE"16V"
PACK_TYPE"0402"
TOLERANCE"10%"
VALUE"0.22UF"
PART_NUMBER"A36096-155"
LOCATION"C2R9";
"A"
$PN"1"32;
"B"
$PN"2"31;
%"TAP"
"7","(-5475,1100)","0","mstr_standard","I148";
;
HDL_TAP"TRUE"
BODY_TYPE"PLUMBING"
CDS_LIB"mstr_standard";
"B \NAC \NWC"4;
"S \NAC"
BN"7"31;
%"TAP"
"7","(-4100,2100)","0","mstr_standard","I25";
;
HDL_TAP"TRUE"
BODY_TYPE"PLUMBING"
CDS_LIB"mstr_standard";
"B \NAC \NWC"3;
"S \NAC"
BN"0"63;
%"CAP"
"1","(-4300,2350)","2","mstr_discrete","I26";
;
ROOM"PCIE_STEERING"
CDS_LOCATION"C1R4"
$SEC"1"
CDS_SEC"1"
CDS_LIB"mstr_discrete"
BOM_COST"IO_SLOT"
MATERIAL"X7R"
VOLTAGE"16V"
PACK_TYPE"0402"
TOLERANCE"10%"
VALUE"0.22UF"
PART_NUMBER"A36096-155"
LOCATION"C1R4";
"A"
$PN"1"64;
"B"
$PN"2"62;
%"TAP"
"7","(-4300,2100)","0","mstr_standard","I27";
;
HDL_TAP"TRUE"
BODY_TYPE"PLUMBING"
CDS_LIB"mstr_standard";
"B \NAC \NWC"3;
"S \NAC"
BN"1"62;
%"TAP"
"3","(-4075,1900)","0","mstr_standard","I28";
;
HDL_TAP"TRUE"
BODY_TYPE"PLUMBING"
CDS_LIB"mstr_standard";
"B \NAC \NWC"1;
"S \NAC"
BN"0"68;
%"CAP"
"1","(-4075,1650)","2","mstr_discrete","I29";
;
ROOM"PCIE_STEERING"
CDS_LOCATION"C1R1"
$SEC"1"
CDS_SEC"1"
CDS_LIB"mstr_discrete"
BOM_COST"IO_SLOT"
MATERIAL"X7R"
VOLTAGE"16V"
PACK_TYPE"0402"
TOLERANCE"10%"
VALUE"0.22UF"
PART_NUMBER"A36096-155"
LOCATION"C1R1";
"A"
$PN"1"68;
"B"
$PN"2"67;
%"TAP"
"3","(-4275,1900)","0","mstr_standard","I30";
;
HDL_TAP"TRUE"
BODY_TYPE"PLUMBING"
CDS_LIB"mstr_standard";
"B \NAC \NWC"1;
"S \NAC"
BN"1"42;
%"TAP"
"7","(-4075,1100)","0","mstr_standard","I36";
;
HDL_TAP"TRUE"
BODY_TYPE"PLUMBING"
CDS_LIB"mstr_standard";
"B \NAC \NWC"4;
"S \NAC"
BN"0"67;
%"CAP"
"1","(-4275,1350)","2","mstr_discrete","I37";
;
ROOM"PCIE_STEERING"
CDS_LOCATION"C1R3"
$SEC"1"
CDS_SEC"1"
CDS_LIB"mstr_discrete"
BOM_COST"IO_SLOT"
MATERIAL"X7R"
VOLTAGE"16V"
PACK_TYPE"0402"
TOLERANCE"10%"
VALUE"0.22UF"
PART_NUMBER"A36096-155"
LOCATION"C1R3";
"A"
$PN"1"42;
"B"
$PN"2"41;
%"TAP"
"7","(-4275,1100)","0","mstr_standard","I38";
;
HDL_TAP"TRUE"
BODY_TYPE"PLUMBING"
CDS_LIB"mstr_standard";
"B \NAC \NWC"4;
"S \NAC"
BN"1"41;
%"TAP"
"3","(-4500,2900)","0","mstr_standard","I39";
;
HDL_TAP"TRUE"
BODY_TYPE"PLUMBING"
CDS_LIB"mstr_standard";
"B \NAC \NWC"2;
"S \NAC"
BN"2"65;
%"CAP"
"1","(-4500,2650)","2","mstr_discrete","I40";
;
ROOM"PCIE_STEERING"
CDS_LOCATION"C1R6"
$SEC"1"
CDS_SEC"1"
CDS_LIB"mstr_discrete"
MATERIAL"X7R"
VOLTAGE"16V"
PACK_TYPE"0402"
TOLERANCE"10%"
VALUE"0.22UF"
PART_NUMBER"A36096-155"
LOCATION"C1R6";
"A"
$PN"1"65;
"B"
$PN"2"61;
%"TAP"
"3","(-4700,2900)","0","mstr_standard","I41";
;
HDL_TAP"TRUE"
BODY_TYPE"PLUMBING"
CDS_LIB"mstr_standard";
"B \NAC \NWC"2;
"S \NAC"
BN"3"59;
%"TAP"
"7","(-4500,2100)","0","mstr_standard","I54";
;
HDL_TAP"TRUE"
BODY_TYPE"PLUMBING"
CDS_LIB"mstr_standard";
"B \NAC \NWC"3;
"S \NAC"
BN"2"61;
%"CAP"
"1","(-4700,2350)","2","mstr_discrete","I55";
;
ROOM"PCIE_STEERING"
CDS_LOCATION"C1R8"
$SEC"1"
CDS_SEC"1"
CDS_LIB"mstr_discrete"
MATERIAL"X7R"
VOLTAGE"16V"
PACK_TYPE"0402"
TOLERANCE"10%"
VALUE"0.22UF"
PART_NUMBER"A36096-155"
LOCATION"C1R8";
"A"
$PN"1"59;
"B"
$PN"2"57;
%"TAP"
"7","(-4700,2100)","0","mstr_standard","I56";
;
HDL_TAP"TRUE"
BODY_TYPE"PLUMBING"
CDS_LIB"mstr_standard";
"B \NAC \NWC"3;
"S \NAC"
BN"3"57;
%"TAP"
"3","(-4475,1900)","0","mstr_standard","I58";
;
HDL_TAP"TRUE"
BODY_TYPE"PLUMBING"
CDS_LIB"mstr_standard";
"B \NAC \NWC"1;
"S \NAC"
BN"2"44;
%"CAP"
"1","(-4475,1650)","2","mstr_discrete","I59";
;
ROOM"PCIE_STEERING"
CDS_LOCATION"C1R5"
$SEC"1"
CDS_SEC"1"
CDS_LIB"mstr_discrete"
BOM_COST"IO_SLOT"
MATERIAL"X7R"
VOLTAGE"16V"
PACK_TYPE"0402"
TOLERANCE"10%"
VALUE"0.22UF"
PART_NUMBER"A36096-155"
LOCATION"C1R5";
"A"
$PN"1"44;
"B"
$PN"2"43;
%"TAP"
"3","(-4675,1900)","0","mstr_standard","I60";
;
HDL_TAP"TRUE"
BODY_TYPE"PLUMBING"
CDS_LIB"mstr_standard";
"B \NAC \NWC"1;
"S \NAC"
BN"3"39;
%"TAP"
"7","(-4475,1100)","0","mstr_standard","I69";
;
HDL_TAP"TRUE"
BODY_TYPE"PLUMBING"
CDS_LIB"mstr_standard";
"B \NAC \NWC"4;
"S \NAC"
BN"2"43;
%"CAP"
"1","(-4675,1350)","2","mstr_discrete","I70";
;
ROOM"PCIE_STEERING"
CDS_LOCATION"C1R7"
$SEC"1"
CDS_SEC"1"
CDS_LIB"mstr_discrete"
BOM_COST"IO_SLOT"
MATERIAL"X7R"
VOLTAGE"16V"
PACK_TYPE"0402"
TOLERANCE"10%"
VALUE"0.22UF"
PART_NUMBER"A36096-155"
LOCATION"C1R7";
"A"
$PN"1"39;
"B"
$PN"2"36;
%"TAP"
"7","(-4675,1100)","0","mstr_standard","I72";
;
HDL_TAP"TRUE"
BODY_TYPE"PLUMBING"
CDS_LIB"mstr_standard";
"B \NAC \NWC"4;
"S \NAC"
BN"3"36;
%"TAP"
"7","(-5900,2100)","0","mstr_standard","I73";
;
HDL_TAP"TRUE"
BODY_TYPE"PLUMBING"
CDS_LIB"mstr_standard";
"B \NAC \NWC"3;
"S \NAC"
BN"9"45;
%"TAP"
"7","(-5650,1100)","0","mstr_standard","I74";
;
HDL_TAP"TRUE"
BODY_TYPE"PLUMBING"
CDS_LIB"mstr_standard";
"B \NAC \NWC"4;
"S \NAC"
BN"8"26;
%"TAP"
"3","(-5700,2900)","0","mstr_standard","I75";
;
HDL_TAP"TRUE"
BODY_TYPE"PLUMBING"
CDS_LIB"mstr_standard";
"B \NAC \NWC"2;
"S \NAC"
BN"8"50;
%"CAP"
"1","(-5700,2650)","2","mstr_discrete","I76";
;
ROOM"PCIE_STEERING"
CDS_LOCATION"C2M14"
$SEC"1"
CDS_SEC"1"
BOM_COST"IO_SLOT"
CDS_LIB"mstr_discrete"
MATERIAL"X7R"
VOLTAGE"16V"
PACK_TYPE"0402"
TOLERANCE"10%"
VALUE"0.22UF"
PART_NUMBER"A36096-155"
LOCATION"C2M14";
"A"
$PN"1"50;
"B"
$PN"2"47;
%"TAP"
"7","(-5700,2100)","0","mstr_standard","I77";
;
HDL_TAP"TRUE"
BODY_TYPE"PLUMBING"
CDS_LIB"mstr_standard";
"B \NAC \NWC"3;
"S \NAC"
BN"8"47;
%"CAP"
"1","(-5900,2350)","2","mstr_discrete","I78";
;
ROOM"PCIE_STEERING"
CDS_LOCATION"C1M18"
$SEC"1"
CDS_SEC"1"
BOM_COST"IO_SLOT"
CDS_LIB"mstr_discrete"
MATERIAL"X7R"
VOLTAGE"16V"
PACK_TYPE"0402"
TOLERANCE"10%"
VALUE"0.22UF"
PART_NUMBER"A36096-155"
LOCATION"C1M18";
"A"
$PN"1"48;
"B"
$PN"2"45;
%"TAP"
"3","(-5900,2900)","0","mstr_standard","I79";
;
HDL_TAP"TRUE"
BODY_TYPE"PLUMBING"
CDS_LIB"mstr_standard";
"B \NAC \NWC"2;
"S \NAC"
BN"9"48;
%"TAP"
"3","(-6100,2900)","0","mstr_standard","I80";
;
HDL_TAP"TRUE"
BODY_TYPE"PLUMBING"
CDS_LIB"mstr_standard";
"B \NAC \NWC"2;
"S \NAC"
BN"10"49;
%"TAP"
"3","(-6300,2900)","0","mstr_standard","I81";
;
HDL_TAP"TRUE"
BODY_TYPE"PLUMBING"
CDS_LIB"mstr_standard";
"B \NAC \NWC"2;
"S \NAC"
BN"11"23;
%"CAP"
"1","(-6100,2650)","2","mstr_discrete","I82";
;
ROOM"PCIE_STEERING"
CDS_LOCATION"C1M16"
$SEC"1"
CDS_SEC"1"
BOM_COST"IO_SLOT"
CDS_LIB"mstr_discrete"
MATERIAL"X7R"
VOLTAGE"16V"
PACK_TYPE"0402"
TOLERANCE"10%"
VALUE"0.22UF"
PART_NUMBER"A36096-155"
LOCATION"C1M16";
"A"
$PN"1"49;
"B"
$PN"2"46;
%"TAP"
"7","(-6100,2100)","0","mstr_standard","I83";
;
HDL_TAP"TRUE"
BODY_TYPE"PLUMBING"
CDS_LIB"mstr_standard";
"B \NAC \NWC"3;
"S \NAC"
BN"10"46;
%"TAP"
"7","(-6300,2100)","0","mstr_standard","I84";
;
HDL_TAP"TRUE"
BODY_TYPE"PLUMBING"
CDS_LIB"mstr_standard";
"B \NAC \NWC"3;
"S \NAC"
BN"11"22;
%"CAP"
"1","(-6300,2350)","2","mstr_discrete","I85";
;
ROOM"PCIE_STEERING"
CDS_LOCATION"C1M14"
$SEC"1"
CDS_SEC"1"
BOM_COST"IO_SLOT"
CDS_LIB"mstr_discrete"
MATERIAL"X7R"
VOLTAGE"16V"
PACK_TYPE"0402"
TOLERANCE"10%"
VALUE"0.22UF"
PART_NUMBER"A36096-155"
LOCATION"C1M14";
"A"
$PN"1"23;
"B"
$PN"2"22;
%"CAP"
"1","(-5650,1650)","2","mstr_discrete","I86";
;
ROOM"PCIE_STEERING"
CDS_LOCATION"C2M15"
$SEC"1"
CDS_SEC"1"
BOM_COST"IO_SLOT"
CDS_LIB"mstr_discrete"
MATERIAL"X7R"
VOLTAGE"16V"
PACK_TYPE"0402"
TOLERANCE"10%"
VALUE"0.22UF"
PART_NUMBER"A36096-155"
LOCATION"C2M15";
"A"
$PN"1"30;
"B"
$PN"2"26;
%"TAP"
"3","(-5650,1900)","0","mstr_standard","I87";
;
HDL_TAP"TRUE"
BODY_TYPE"PLUMBING"
CDS_LIB"mstr_standard";
"B \NAC \NWC"1;
"S \NAC"
BN"8"30;
%"TAP"
"3","(-5850,1900)","0","mstr_standard","I88";
;
HDL_TAP"TRUE"
BODY_TYPE"PLUMBING"
CDS_LIB"mstr_standard";
"B \NAC \NWC"1;
"S \NAC"
BN"9"28;
%"TAP"
"7","(-5850,1100)","0","mstr_standard","I89";
;
HDL_TAP"TRUE"
BODY_TYPE"PLUMBING"
CDS_LIB"mstr_standard";
"B \NAC \NWC"4;
"S \NAC"
BN"9"25;
%"TAP"
"3","(-4100,2900)","0","mstr_standard","I9";
;
HDL_TAP"TRUE"
BODY_TYPE"PLUMBING"
CDS_LIB"mstr_standard";
"B \NAC \NWC"2;
"S \NAC"
BN"0"66;
%"CAP"
"1","(-5850,1350)","2","mstr_discrete","I90";
;
ROOM"PCIE_STEERING"
CDS_LOCATION"C1M19"
$SEC"1"
CDS_SEC"1"
BOM_COST"IO_SLOT"
CDS_LIB"mstr_discrete"
MATERIAL"X7R"
VOLTAGE"16V"
PACK_TYPE"0402"
TOLERANCE"10%"
VALUE"0.22UF"
PART_NUMBER"A36096-155"
LOCATION"C1M19";
"A"
$PN"1"28;
"B"
$PN"2"25;
%"TAP"
"3","(-6050,1900)","0","mstr_standard","I91";
;
HDL_TAP"TRUE"
BODY_TYPE"PLUMBING"
CDS_LIB"mstr_standard";
"B \NAC \NWC"1;
"S \NAC"
BN"10"29;
%"CAP"
"1","(-6050,1650)","2","mstr_discrete","I92";
;
ROOM"PCIE_STEERING"
CDS_LOCATION"C1M17"
$SEC"1"
CDS_SEC"1"
BOM_COST"IO_SLOT"
CDS_LIB"mstr_discrete"
MATERIAL"X7R"
VOLTAGE"16V"
PACK_TYPE"0402"
TOLERANCE"10%"
VALUE"0.22UF"
PART_NUMBER"A36096-155"
LOCATION"C1M17";
"A"
$PN"1"29;
"B"
$PN"2"27;
%"TAP"
"3","(-6250,1900)","0","mstr_standard","I93";
;
HDL_TAP"TRUE"
BODY_TYPE"PLUMBING"
CDS_LIB"mstr_standard";
"B \NAC \NWC"1;
"S \NAC"
BN"11"12;
%"TAP"
"7","(-6050,1100)","0","mstr_standard","I94";
;
HDL_TAP"TRUE"
BODY_TYPE"PLUMBING"
CDS_LIB"mstr_standard";
"B \NAC \NWC"4;
"S \NAC"
BN"10"27;
%"CAP"
"1","(-6250,1350)","2","mstr_discrete","I95";
;
ROOM"PCIE_STEERING"
CDS_LOCATION"C1M15"
$SEC"1"
CDS_SEC"1"
BOM_COST"IO_SLOT"
CDS_LIB"mstr_discrete"
MATERIAL"X7R"
VOLTAGE"16V"
PACK_TYPE"0402"
TOLERANCE"10%"
VALUE"0.22UF"
PART_NUMBER"A36096-155"
LOCATION"C1M15";
"A"
$PN"1"12;
"B"
$PN"2"10;
%"TAP"
"7","(-6250,1100)","0","mstr_standard","I96";
;
HDL_TAP"TRUE"
BODY_TYPE"PLUMBING"
CDS_LIB"mstr_standard";
"B \NAC \NWC"4;
"S \NAC"
BN"11"10;
%"TAP"
"3","(-6500,2900)","0","mstr_standard","I97";
;
HDL_TAP"TRUE"
BODY_TYPE"PLUMBING"
CDS_LIB"mstr_standard";
"B \NAC \NWC"2;
"S \NAC"
BN"12"24;
%"TAP"
"3","(-6700,2900)","0","mstr_standard","I98";
;
HDL_TAP"TRUE"
BODY_TYPE"PLUMBING"
CDS_LIB"mstr_standard";
"B \NAC \NWC"2;
"S \NAC"
BN"13"18;
%"TAP"
"3","(-6900,2900)","0","mstr_standard","I99";
;
HDL_TAP"TRUE"
BODY_TYPE"PLUMBING"
CDS_LIB"mstr_standard";
"B \NAC \NWC"2;
"S \NAC"
BN"14"20;
END.
